(kicad_pcb
	(version 20241229)
	(generator "pcbnew")
	(generator_version "9.0")
	(general
		(thickness 0.876)
		(legacy_teardrops no)
	)
	(paper "A4")
	(title_block
		(rev "1.2.2")
		(comment 9 "footprints 16-18 of 20")
	)
	(layers
		(0 "F.Cu" signal)
		(4 "In1.Cu" signal)
		(6 "In2.Cu" signal)
		(2 "B.Cu" signal)
		(9 "F.Adhes" user "F.Adhesive")
		(11 "B.Adhes" user "B.Adhesive")
		(13 "F.Paste" user)
		(15 "B.Paste" user)
		(5 "F.SilkS" user "F.Silkscreen")
		(7 "B.SilkS" user "B.Silkscreen")
		(1 "F.Mask" user)
		(3 "B.Mask" user)
		(17 "Dwgs.User" user "User.Drawings")
		(19 "Cmts.User" user "User.Comments")
		(21 "Eco1.User" user "User.Eco1")
		(23 "Eco2.User" user "User.Eco2")
		(25 "Edge.Cuts" user)
		(27 "Margin" user)
		(31 "F.CrtYd" user "F.Courtyard")
		(29 "B.CrtYd" user "B.Courtyard")
		(35 "F.Fab" user)
		(33 "B.Fab" user)
	)
	(footprint "antmicro-footprints:C_0402_1005Metric"
		(layer "B.Cu")
		(at 137.530059 112.367277 180)
		(descr "Capacitor SMD 0402")
		(tags "capacitor SMD 0402")
		(property "Reference" "C5"
			(at 1.47 -0.06 0)
			(layer "B.SilkS")
			(effects
				(font
					(size 0.7 0.7)
					(thickness 0.15)
				)
				(justify mirror)
			)
		)
		(property "Value" "C_100n_16V_X7R_0402"
			(at 0 -1.17 0)
			(layer "B.Fab")
			(effects
				(font
					(size 1 1)
					(thickness 0.15)
				)
				(justify mirror)
			)
		)
		(property "Datasheet" "https://www.kemet.com/en/us/capacitors/product/C0402C104J4RAC7411.html"
			(at 0 0 180)
			(layer "F.Fab")
			(hide yes)
			(effects
				(font
					(size 1.27 1.27)
					(thickness 0.15)
				)
			)
		)
		(property "Description" "SMD Multilayer Ceramic Capacitor, 100nF, 50V, 0402, ±5%, X7R"
			(at 0 0 180)
			(layer "F.Fab")
			(hide yes)
			(effects
				(font
					(size 1.27 1.27)
					(thickness 0.15)
				)
			)
		)
		(property "Author" "Antmicro"
			(at 275.060118 224.734554 0)
			(layer "B.Fab")
			(hide yes)
			(effects
				(font
					(size 1 1)
					(thickness 0.15)
				)
				(justify mirror)
			)
		)
		(property "Dielectric" "X7R"
			(at 275.060118 224.734554 0)
			(layer "B.Fab")
			(hide yes)
			(effects
				(font
					(size 1 1)
					(thickness 0.15)
				)
				(justify mirror)
			)
		)
		(property "License" "Apache-2.0"
			(at 275.060118 224.734554 0)
			(layer "B.Fab")
			(hide yes)
			(effects
				(font
					(size 1 1)
					(thickness 0.15)
				)
				(justify mirror)
			)
		)
		(property "MPN" "C0402C104J4RAC7411"
			(at 275.060118 224.734554 0)
			(layer "B.Fab")
			(hide yes)
			(effects
				(font
					(size 1 1)
					(thickness 0.15)
				)
				(justify mirror)
			)
		)
		(property "Manufacturer" "KEMET"
			(at 275.060118 224.734554 0)
			(layer "B.Fab")
			(hide yes)
			(effects
				(font
					(size 1 1)
					(thickness 0.15)
				)
				(justify mirror)
			)
		)
		(property "Val" "100n"
			(at 275.060118 224.734554 0)
			(layer "B.Fab")
			(hide yes)
			(effects
				(font
					(size 1 1)
					(thickness 0.15)
				)
				(justify mirror)
			)
		)
		(property "Voltage" "16V"
			(at 275.060118 224.734554 0)
			(layer "B.Fab")
			(hide yes)
			(effects
				(font
					(size 1 1)
					(thickness 0.15)
				)
				(justify mirror)
			)
		)
		(sheetname "/")
		(sheetfile "m2-pcie-adapter.kicad_sch")
		(attr smd)
		(fp_rect
			(start -0.925 0.47)
			(end 0.925 -0.47)
			(stroke
				(width 0.05)
				(type default)
			)
			(fill no)
			(layer "B.CrtYd")
		)
		(fp_line
			(start 0.504 0.25)
			(end 0.504 -0.248)
			(stroke
				(width 0.15)
				(type solid)
			)
			(layer "B.Fab")
		)
		(fp_line
			(start 0.504 -0.248)
			(end -0.494 -0.248)
			(stroke
				(width 0.15)
				(type solid)
			)
			(layer "B.Fab")
		)
		(fp_line
			(start -0.494 0.25)
			(end 0.504 0.25)
			(stroke
				(width 0.15)
				(type solid)
			)
			(layer "B.Fab")
		)
		(fp_line
			(start -0.494 -0.248)
			(end -0.494 0.25)
			(stroke
				(width 0.15)
				(type solid)
			)
			(layer "B.Fab")
		)
		(fp_text user "${REFERENCE}"
			(at 0 0 0)
			(layer "B.Fab")
			(effects
				(font
					(size 0.25 0.25)
					(thickness 0.04)
				)
				(justify mirror)
			)
		)
		(pad "1" smd roundrect
			(at -0.48 0 180)
			(size 0.59 0.64)
			(layers "B.Cu" "B.Mask" "B.Paste")
			(roundrect_rratio 0.25)
			(net 62 "/+3V3_AUX")
			(pintype "passive")
		)
		(pad "2" smd roundrect
			(at 0.48 0 180)
			(size 0.59 0.64)
			(layers "B.Cu" "B.Mask" "B.Paste")
			(roundrect_rratio 0.25)
			(net 60 "GND")
			(pintype "passive")
		)
	)
	(footprint "antmicro-footprints:R_0402_1005Metric"
		(layer "B.Cu")
		(at 135.680059 109.087277 90)
		(descr "Resistor SMD 0402")
		(tags "resistor SMD 0402")
		(property "Reference" "R4"
			(at -1.52 0.01 270)
			(layer "B.SilkS")
			(effects
				(font
					(size 0.7 0.7)
					(thickness 0.15)
				)
				(justify mirror)
			)
		)
		(property "Value" "R_0R_0402"
			(at 0 -1.17 90)
			(layer "B.Fab")
			(effects
				(font
					(size 1 1)
					(thickness 0.15)
				)
				(justify mirror)
			)
		)
		(property "Datasheet" "https://industrial.panasonic.com/cdbs/www-data/pdf/RDA0000/AOA0000C301.pdf"
			(at 0 0 90)
			(layer "F.Fab")
			(hide yes)
			(effects
				(font
					(size 1.27 1.27)
					(thickness 0.15)
				)
			)
		)
		(property "Description" "SMD Chip Resistor, Jumper, 0 ohm, 100 mW, 0402 [1005 Metric], Thick Film, General Purpose"
			(at 0 0 90)
			(layer "F.Fab")
			(hide yes)
			(effects
				(font
					(size 1.27 1.27)
					(thickness 0.15)
				)
			)
		)
		(property "Author" "Antmicro"
			(at 244.767336 -26.592782 0)
			(layer "B.Fab")
			(hide yes)
			(effects
				(font
					(size 1 1)
					(thickness 0.15)
				)
				(justify mirror)
			)
		)
		(property "Current" "1A"
			(at 244.767336 -26.592782 0)
			(layer "B.Fab")
			(hide yes)
			(effects
				(font
					(size 1 1)
					(thickness 0.15)
				)
				(justify mirror)
			)
		)
		(property "License" "Apache-2.0"
			(at 244.767336 -26.592782 0)
			(layer "B.Fab")
			(hide yes)
			(effects
				(font
					(size 1 1)
					(thickness 0.15)
				)
				(justify mirror)
			)
		)
		(property "MPN" "ERJ2GE0R00X"
			(at 244.767336 -26.592782 0)
			(layer "B.Fab")
			(hide yes)
			(effects
				(font
					(size 1 1)
					(thickness 0.15)
				)
				(justify mirror)
			)
		)
		(property "Manufacturer" "Panasonic"
			(at 244.767336 -26.592782 0)
			(layer "B.Fab")
			(hide yes)
			(effects
				(font
					(size 1 1)
					(thickness 0.15)
				)
				(justify mirror)
			)
		)
		(property "Public" "False"
			(at 244.767336 -26.592782 0)
			(layer "B.Fab")
			(hide yes)
			(effects
				(font
					(size 1 1)
					(thickness 0.15)
				)
				(justify mirror)
			)
		)
		(property "Tolerance" ""
			(at 244.767336 -26.592782 0)
			(layer "B.Fab")
			(hide yes)
			(effects
				(font
					(size 1 1)
					(thickness 0.15)
				)
				(justify mirror)
			)
		)
		(property "Val" "0R"
			(at 244.767336 -26.592782 0)
			(layer "B.Fab")
			(hide yes)
			(effects
				(font
					(size 1 1)
					(thickness 0.15)
				)
				(justify mirror)
			)
		)
		(sheetname "/")
		(sheetfile "m2-pcie-adapter.kicad_sch")
		(attr smd)
		(fp_rect
			(start -0.925 0.47)
			(end 0.925 -0.47)
			(stroke
				(width 0.05)
				(type default)
			)
			(fill no)
			(layer "B.CrtYd")
		)
		(fp_rect
			(start -0.5 0.25)
			(end 0.5 -0.25)
			(stroke
				(width 0.15)
				(type solid)
			)
			(fill no)
			(layer "B.Fab")
		)
		(fp_text user "${REFERENCE}"
			(at 0 0 90)
			(layer "B.Fab")
			(effects
				(font
					(size 0.25 0.25)
					(thickness 0.04)
				)
				(justify mirror)
			)
		)
		(pad "1" smd roundrect
			(at -0.48 0 90)
			(size 0.59 0.64)
			(layers "B.Cu" "B.Mask" "B.Paste")
			(roundrect_rratio 0.25)
			(net 11 "Net-(J1-PWRGD)")
			(pintype "passive")
		)
		(pad "2" smd roundrect
			(at 0.48 0 90)
			(size 0.59 0.64)
			(layers "B.Cu" "B.Mask" "B.Paste")
			(roundrect_rratio 0.25)
			(net 59 "/PWRGD")
			(pintype "passive")
		)
	)
	(footprint "antmicro-footprints:R_0402_1005Metric"
		(layer "B.Cu")
		(at 137.200059 109.037277 -90)
		(descr "Resistor SMD 0402")
		(tags "resistor SMD 0402")
		(property "Reference" "R3"
			(at 1.58 -0.04 90)
			(layer "B.SilkS")
			(effects
				(font
					(size 0.7 0.7)
					(thickness 0.15)
				)
				(justify mirror)
			)
		)
		(property "Value" "R_0R_0402"
			(at 0 -1.17 90)
			(layer "B.Fab")
			(effects
				(font
					(size 1 1)
					(thickness 0.15)
				)
				(justify mirror)
			)
		)
		(property "Datasheet" "https://industrial.panasonic.com/cdbs/www-data/pdf/RDA0000/AOA0000C301.pdf"
			(at 0 0 270)
			(layer "F.Fab")
			(hide yes)
			(effects
				(font
					(size 1.27 1.27)
					(thickness 0.15)
				)
			)
		)
		(property "Description" "SMD Chip Resistor, Jumper, 0 ohm, 100 mW, 0402 [1005 Metric], Thick Film, General Purpose"
			(at 0 0 270)
			(layer "F.Fab")
			(hide yes)
			(effects
				(font
					(size 1.27 1.27)
					(thickness 0.15)
				)
			)
		)
		(property "Author" "Antmicro"
			(at 28.162782 246.237336 0)
			(layer "B.Fab")
			(hide yes)
			(effects
				(font
					(size 1 1)
					(thickness 0.15)
				)
				(justify mirror)
			)
		)
		(property "Current" "1A"
			(at 28.162782 246.237336 0)
			(layer "B.Fab")
			(hide yes)
			(effects
				(font
					(size 1 1)
					(thickness 0.15)
				)
				(justify mirror)
			)
		)
		(property "License" "Apache-2.0"
			(at 28.162782 246.237336 0)
			(layer "B.Fab")
			(hide yes)
			(effects
				(font
					(size 1 1)
					(thickness 0.15)
				)
				(justify mirror)
			)
		)
		(property "MPN" "ERJ2GE0R00X"
			(at 28.162782 246.237336 0)
			(layer "B.Fab")
			(hide yes)
			(effects
				(font
					(size 1 1)
					(thickness 0.15)
				)
				(justify mirror)
			)
		)
		(property "Manufacturer" "Panasonic"
			(at 28.162782 246.237336 0)
			(layer "B.Fab")
			(hide yes)
			(effects
				(font
					(size 1 1)
					(thickness 0.15)
				)
				(justify mirror)
			)
		)
		(property "Public" "False"
			(at 28.162782 246.237336 0)
			(layer "B.Fab")
			(hide yes)
			(effects
				(font
					(size 1 1)
					(thickness 0.15)
				)
				(justify mirror)
			)
		)
		(property "Tolerance" ""
			(at 28.162782 246.237336 0)
			(layer "B.Fab")
			(hide yes)
			(effects
				(font
					(size 1 1)
					(thickness 0.15)
				)
				(justify mirror)
			)
		)
		(property "Val" "0R"
			(at 28.162782 246.237336 0)
			(layer "B.Fab")
			(hide yes)
			(effects
				(font
					(size 1 1)
					(thickness 0.15)
				)
				(justify mirror)
			)
		)
		(sheetname "/")
		(sheetfile "m2-pcie-adapter.kicad_sch")
		(attr smd)
		(fp_rect
			(start -0.925 0.47)
			(end 0.925 -0.47)
			(stroke
				(width 0.05)
				(type default)
			)
			(fill no)
			(layer "B.CrtYd")
		)
		(fp_rect
			(start -0.5 0.25)
			(end 0.5 -0.25)
			(stroke
				(width 0.15)
				(type solid)
			)
			(fill no)
			(layer "B.Fab")
		)
		(fp_text user "${REFERENCE}"
			(at 0 0 90)
			(layer "B.Fab")
			(effects
				(font
					(size 0.25 0.25)
					(thickness 0.04)
				)
				(justify mirror)
			)
		)
		(pad "1" smd roundrect
			(at -0.48 0 270)
			(size 0.59 0.64)
			(layers "B.Cu" "B.Mask" "B.Paste")
			(roundrect_rratio 0.25)
			(net 63 "/WAKE#")
			(pintype "passive")
		)
		(pad "2" smd roundrect
			(at 0.48 0 270)
			(size 0.59 0.64)
			(layers "B.Cu" "B.Mask" "B.Paste")
			(roundrect_rratio 0.25)
			(net 5 "Net-(J1-WAKE#)")
			(pintype "passive")
		)
	)
)
